# BASEBOARD_FAB2 (Tioga Pass) — schematic netlist excerpt (pin names and nets, part order shuffled) for the footprints in the layout excerpt that follows; sources: Cadence DE-HDL packaged netlist, KiCad conversion of Wiwynn_Tioga_Pass_MB.brd

T1D12  TEST-PAD-12P-1-GP-U  pkg DISCRET-GB1  page 257
  DP  = L14_85OHM_5INCH_DN
  DN  = L14_85OHM_5INCH_DP
  GND(0)  = GND
  GND(1)  = GND
  GND(2)  = GND
  GND(3)  = GND
  GND(4)  = GND
  GND(5)  = GND
  GND(6)  = GND
  GND(7)  = GND
  GND(8)  = GND
  GND(9)  = GND

R2L8  RES  10.0 1% CHIP  pkg 0603  page 235 : A = VSENSE_P1V05_PCH_STBY_AVSP ; B = VR_P1V05_PCH_STBY_AVSP

(kicad_pcb
	(version 20260206)
	(generator "pcbnew")
	(generator_version "10.0")
	(general
		(thickness 1.6)
		(legacy_teardrops no)
	)
	(paper "A4")
	(title_block
		(title "Wiwynn_Tioga_Pass_MB.brd")
		(comment 1 "Tioga Pass / footprints 3919-3920 of 4770")
	)
	(layers
		(0 "F.Cu" signal "TOP")
		(4 "In1.Cu" signal "L2GND")
		(6 "In2.Cu" signal "L3")
		(8 "In3.Cu" signal "L4GND")
		(10 "In4.Cu" signal "L5")
		(12 "In5.Cu" signal "L6GND")
		(14 "In6.Cu" signal "L7VCC")
		(16 "In7.Cu" signal "L8VCC")
		(18 "In8.Cu" signal "L9GND")
		(20 "In9.Cu" signal "L10")
		(22 "In10.Cu" signal "L11GND")
		(24 "In11.Cu" signal "L12")
		(26 "In12.Cu" signal "L13GND")
		(2 "B.Cu" signal "BOTTOM")
		(9 "F.Adhes" user "F.Adhesive")
		(11 "B.Adhes" user "B.Adhesive")
		(13 "F.Paste" user "Package Geometry/Pastemask Top")
		(15 "B.Paste" user "Package Geometry/Pastemask Bottom")
		(5 "F.SilkS" user "Ref Des/Silkscreen Top")
		(7 "B.SilkS" user "Ref Des/Silkscreen Bottom")
		(1 "F.Mask" user "Board Geometry/Soldermask Top")
		(3 "B.Mask" user "Board Geometry/Soldermask Bottom")
		(17 "Dwgs.User" user "User.Drawings")
		(19 "Cmts.User" user "User.Comments")
		(21 "Eco1.User" user "User.Eco1")
		(23 "Eco2.User" user "User.Eco2")
		(25 "Edge.Cuts" user "Board Geometry/Outline")
		(27 "Margin" user)
		(31 "F.CrtYd" user "Package Geometry/Place Bound Top")
		(29 "B.CrtYd" user "Package Geometry/Place Bound Bottom")
		(35 "F.Fab" user "Ref Des/Assembly Top")
		(33 "B.Fab" user "Ref Des/Assembly Bottom")
	)
	(footprint ""
		(layer "B.Cu")
		(at 393.1412 -156.083 90)
		(property "Reference" "R2L8"
			(at 0 0 90)
			(layer "B.SilkS")
			(hide yes)
			(effects
				(font
					(size 1.27 1.27)
				)
				(justify mirror)
			)
		)
		(property "Value" ""
			(at 0 0 90)
			(layer "B.Fab")
			(effects
				(font
					(size 1.27 1.27)
				)
				(justify mirror)
			)
		)
		(duplicate_pad_numbers_are_jumpers no)
		(fp_poly
			(pts
				(xy 0.4953 -0.2032) (xy -0.4953 -0.2032) (xy -0.4953 1.6002) (xy 0.4953 1.6002)
			)
			(stroke
				(width 0)
				(type default)
			)
			(fill no)
			(layer "B.CrtYd")
		)
		(fp_line
			(start 0.4953 -0.2032)
			(end -0.4953 -0.2032)
			(stroke
				(width 0.1)
				(type default)
			)
			(layer "B.Fab")
		)
		(fp_line
			(start -0.4953 -0.2032)
			(end -0.4953 1.6002)
			(stroke
				(width 0.1)
				(type default)
			)
			(layer "B.Fab")
		)
		(fp_line
			(start 0.4953 1.6002)
			(end 0.4953 -0.2032)
			(stroke
				(width 0.1)
				(type default)
			)
			(layer "B.Fab")
		)
		(fp_line
			(start -0.4953 1.6002)
			(end 0.4953 1.6002)
			(stroke
				(width 0.1)
				(type default)
			)
			(layer "B.Fab")
		)
		(pad "1" smd rect
			(at 0 0 270)
			(size 0.762 0.889)
			(layers "B.Cu" "B.Mask" "B.Paste")
			(net "VSENSE_P1V05_PCH_STBY_AVSP")
		)
		(pad "2" smd rect
			(at 0 1.397 270)
			(size 0.762 0.889)
			(layers "B.Cu" "B.Mask" "B.Paste")
			(net "VR_P1V05_PCH_STBY_AVSP")
		)
		(zone
			(layer "B.Cu")
			(hatch none 0.5)
			(connect_pads
				(clearance 0)
			)
			(min_thickness 0.25)
			(keepout
				(tracks not_allowed)
				(vias allowed)
				(pads allowed)
				(copperpour not_allowed)
				(footprints allowed)
			)
			(placement
				(enabled no)
				(sheetname "")
			)
			(fill
				(thermal_gap 0.5)
				(thermal_bridge_width 0.5)
				(island_removal_mode 0)
			)
			(polygon
				(pts
					(xy 394.0937 -156.464) (xy 393.5857 -156.464) (xy 393.5857 -155.702) (xy 394.0937 -155.702)
				)
			)
		)
		(zone
			(layer "B.Cu")
			(hatch none 0.5)
			(connect_pads
				(clearance 0)
			)
			(min_thickness 0.25)
			(keepout
				(tracks allowed)
				(vias not_allowed)
				(pads allowed)
				(copperpour not_allowed)
				(footprints allowed)
			)
			(placement
				(enabled no)
				(sheetname "")
			)
			(fill
				(thermal_gap 0.5)
				(thermal_bridge_width 0.5)
				(island_removal_mode 0)
			)
			(polygon
				(pts
					(xy 394.0937 -155.702) (xy 393.5857 -155.702) (xy 393.5857 -156.464) (xy 394.0937 -156.464)
				)
			)
		)
	)
	(footprint ""
		(layer "B.Cu")
		(at 13.35024 -165.01618 -90)
		(property "Reference" "T1D12"
			(at 0 0 90)
			(layer "B.SilkS")
			(hide yes)
			(effects
				(font
					(size 1.27 1.27)
				)
				(justify mirror)
			)
		)
		(property "Value" "*"
			(at 3.4036 -4.46405 270)
			(unlocked yes)
			(layer "B.Fab")
			(hide yes)
			(effects
				(font
					(size 0.889 0.889)
					(thickness 0.1524)
				)
				(justify mirror)
			)
		)
		(property "Device Type" "TEST-PAD-12P-1-GP-U_DISCRET-GBA"
			(at 3.4036 -5.98805 270)
			(unlocked yes)
			(layer "B.Fab")
			(hide yes)
			(effects
				(font
					(size 0.889 0.889)
					(thickness 0.1524)
				)
				(justify mirror)
			)
		)
		(duplicate_pad_numbers_are_jumpers no)
		(fp_line
			(start -2.3622 3.4798)
			(end 2.3876 3.4798)
			(stroke
				(width 0.1524)
				(type default)
			)
			(layer "B.SilkS")
		)
		(fp_line
			(start 2.3876 3.4798)
			(end 2.3876 -4.826)
			(stroke
				(width 0.1524)
				(type default)
			)
			(layer "B.SilkS")
		)
		(fp_line
			(start -2.3622 -4.826)
			(end -2.3622 3.4798)
			(stroke
				(width 0.1524)
				(type default)
			)
			(layer "B.SilkS")
		)
		(fp_line
			(start 2.3876 -4.826)
			(end -2.3622 -4.826)
			(stroke
				(width 0.1524)
				(type default)
			)
			(layer "B.SilkS")
		)
		(fp_rect
			(start 2.6416 3.7338)
			(end -2.6162 -5.08)
			(stroke
				(width 0)
				(type default)
			)
			(fill no)
			(layer "B.CrtYd")
		)
		(fp_rect
			(start 2.6416 3.7338)
			(end -2.6162 -5.08)
			(stroke
				(width 0)
				(type default)
			)
			(fill no)
			(layer "B.Fab")
		)
		(pad "1" smd circle
			(at -0.496824 -1.301496 90)
			(size 0.6604 0.6604)
			(layers "B.Cu" "B.Mask" "B.Paste")
			(net "L14_85OHM_5INCH_DN")
		)
		(pad "2" smd circle
			(at 0.503936 -1.301496 90)
			(size 0.6604 0.6604)
			(layers "B.Cu" "B.Mask" "B.Paste")
			(net "L14_85OHM_5INCH_DP")
		)
		(pad "3" smd custom
			(at 0.00889 0.370078 90)
			(size 0.74295 0.74295)
			(layers "B.Cu" "B.Mask" "B.Paste")
			(net "GND")
			(options
				(clearance outline)
				(anchor circle)
			)
			(primitives
				(gr_poly
					(pts
						(xy -2.1209 -1.4859) (xy 2.1209 -1.4859) (xy 2.1209 1.4859) (xy 1.08585 1.4859) (xy 1.08585 0.4699)
						(xy -1.08585 0.4699) (xy -1.08585 1.4859) (xy -2.1209 1.4859)
					)
					(width 0)
					(fill yes)
				)
			)
		)
		(pad "4" thru_hole circle
			(at -1.266444 -3.851656 90)
			(size 1.4478 1.4478)
			(drill 1.0414)
			(layers "*.Cu" "*.Mask")
			(remove_unused_layers no)
			(net "GND")
			(clearance 0.1524)
			(thermal_gap 0.1524)
		)
		(pad "5" thru_hole circle
			(at 1.273556 -3.851656 90)
			(size 1.4478 1.4478)
			(drill 1.0414)
			(layers "*.Cu" "*.Mask")
			(remove_unused_layers no)
			(net "GND")
			(clearance 0.1524)
			(thermal_gap 0.1524)
		)
		(pad "6" thru_hole circle
			(at -1.266444 2.498344 90)
			(size 1.4478 1.4478)
			(drill 1.0414)
			(layers "*.Cu" "*.Mask")
			(remove_unused_layers no)
			(net "GND")
			(clearance 0.1524)
			(thermal_gap 0.1524)
		)
		(pad "7" thru_hole circle
			(at 1.273556 2.498344 90)
			(size 1.4478 1.4478)
			(drill 1.0414)
			(layers "*.Cu" "*.Mask")
			(remove_unused_layers no)
			(net "GND")
			(clearance 0.1524)
			(thermal_gap 0.1524)
		)
		(pad "8" thru_hole circle
			(at -1.27 -0.4572 90)
			(size 0.7112 0.7112)
			(drill 0.4064)
			(layers "*.Cu" "*.Mask")
			(remove_unused_layers no)
			(net "GND")
			(clearance 0.1016)
			(thermal_gap 0.1016)
		)
		(pad "9" thru_hole circle
			(at -1.27 0.762 90)
			(size 0.7112 0.7112)
			(drill 0.4064)
			(layers "*.Cu" "*.Mask")
			(remove_unused_layers no)
			(net "GND")
			(clearance 0.1016)
			(thermal_gap 0.1016)
		)
		(pad "10" thru_hole circle
			(at 0.0254 0.762 90)
			(size 0.7112 0.7112)
			(drill 0.4064)
			(layers "*.Cu" "*.Mask")
			(remove_unused_layers no)
			(net "GND")
			(clearance 0.1016)
			(thermal_gap 0.1016)
		)
		(pad "11" thru_hole circle
			(at 1.27 0.762 90)
			(size 0.7112 0.7112)
			(drill 0.4064)
			(layers "*.Cu" "*.Mask")
			(remove_unused_layers no)
			(net "GND")
			(clearance 0.1016)
			(thermal_gap 0.1016)
		)
		(pad "12" thru_hole circle
			(at 1.27 -0.4572 90)
			(size 0.7112 0.7112)
			(drill 0.4064)
			(layers "*.Cu" "*.Mask")
			(remove_unused_layers no)
			(net "GND")
			(clearance 0.1016)
			(thermal_gap 0.1016)
		)
	)
)
